FILE_TYPE = MACRO_DRAWING;
SET COLOR_WIRE YELLOW;
SET COLOR_PROP ORANGE;
SET COLOR_DOT WHITE;
SET COLOR_ARC YELLOW;
SET COLOR_BODY GREEN;
SET COLOR_NOTE PURPLE;
SET PROP_DISPLAY VALUE;
SET PAGE_NUMBER P160;
FORCEADD QUANTA_TITLE_BLOCK_C..1
(-225 200);
FORCEPROP 1 LAST CUSTOM_TXT_CDS <NAME_2>
J 0
(-3400 250);
FORCEPROP 1 LAST CUSTOM_TXT_CDS <NAME_1>
J 0
(-3400 375);
FORCEPROP 1 LAST CUSTOM_TXT_CDS <Q_NUMBER>
J 0
(-1628 303);
DISPLAY 1.212766 (-1628 303);
FORCEPROP 1 LAST CUSTOM_TXT_CDS <Q_PROJ>
J 0
(-2607 302);
DISPLAY 1.212766 (-2607 302);
FORCEPROP 1 LAST CUSTOM_TXT_CDS <Q_REV>
J 0
(-409 303);
DISPLAY 1.212766 (-409 303);
FORCEPROP 1 LAST CUSTOM_TXT_CDS <CON_LAST_MODIFIED>
J 0
(-2110 215);
DISPLAY 0.978723 (-2110 215);
FORCEPROP 1 LAST CUSTOM_TXT_CDS <CON_PAGE_NUM> OF <CON_TOTAL_PAGES>
J 0
(-671 218);
DISPLAY 0.978723 (-671 218);
FORCEPROP 1 LAST Q_DEPT BU9
J 1
(-3988 249);
DISPLAY 1.957447 (-3988 249);
PAINT GREEN (-3988 249);
FORCEPROP 1 LAST Q_TITLE P12V_FAN MOS SWITCH
J 0
(-9591 226);
DISPLAY 2.446809 (-9591 226);
PAINT GREEN (-9591 226);
FORCEPROP 2 LAST PAGE_BORDER TRUE
J 0
(-8115 5450);
DISPLAY 0.638298 (-8115 5450);
PAINT PINK (-8115 5450);
DISPLAY INVISIBLE (-8115 5450);
FORCEPROP 1 LAST CDS_LMAN_SYM_OUTLINE -9475,6775,100,-125
J 0
(-225 200);
DISPLAY 0.468085 (-225 200);
PAINT GREEN (-225 200);
DISPLAY INVISIBLE (-225 200);
FORCEPROP 2 LAST CDS_LIB pure_quanta
J 0
(-225 200);
PAINT MONO (-225 200);
DISPLAY INVISIBLE (-225 200);
FORCEPROP 1 LAST COMMENT_BODY TRUE
J 0
(-213 187);
DISPLAY 0.978723 (-213 187);
PAINT GREEN (-213 187);
DISPLAY INVISIBLE (-213 187);
FORCEPROP 2 LAST CDS_XR_PAGE_TITLE CR-160 : @T6G_MB_LIB.T6G(SCH_1):PAGE160
J 0
(-8115 5450);
DISPLAY 0.638298 (-8115 5450);
PAINT PINK (-8115 5450);
DISPLAY INVISIBLE (-8115 5450);
FORCEPROP 2 LAST CUSTOM_TXT_CDS <XR_PAGE_TITLE>
J 0
(-8115 5450);
DISPLAY 0.638298 (-8115 5450);
PAINT PINK (-8115 5450);
DISPLAY INVISIBLE (-8115 5450);
FORCEPROP 0 LAST CDS_CON_LAST_MODIFIED Wed Mar 09 20:45:30 2022
J 0
(-2110 215);
PAINT MONO (-2110 215);
DISPLAY INVISIBLE (-2110 215);
QUIT
